(kicad_pcb
	(version 20260206)
	(generator "pcbnew")
	(generator_version "10.0")
	(general
		(thickness 1.6)
		(legacy_teardrops no)
	)
	(paper "A4")
	(title_block
		(title "Bryce Canyon_R.DPB_16317-1_OCP.brd")
		(comment 1 "Bryce Canyon / footprints 1736-1742 of 2099")
	)
	(layers
		(0 "F.Cu" signal "TOP")
		(4 "In1.Cu" signal "L2GND")
		(6 "In2.Cu" signal "L3")
		(8 "In3.Cu" signal "L4VCC")
		(10 "In4.Cu" signal "L5VCC")
		(12 "In5.Cu" signal "L6")
		(14 "In6.Cu" signal "L7GND")
		(2 "B.Cu" signal "BOTTOM")
		(9 "F.Adhes" user "F.Adhesive")
		(11 "B.Adhes" user "B.Adhesive")
		(13 "F.Paste" user "Package Geometry/Pastemask Top")
		(15 "B.Paste" user "Package Geometry/Pastemask Bottom")
		(5 "F.SilkS" user "Ref Des/Silkscreen Top")
		(7 "B.SilkS" user "Ref Des/Silkscreen Bottom")
		(1 "F.Mask" user "Board Geometry/Soldermask Top")
		(3 "B.Mask" user "Board Geometry/Soldermask Bottom")
		(17 "Dwgs.User" user "User.Drawings")
		(19 "Cmts.User" user "User.Comments")
		(21 "Eco1.User" user "User.Eco1")
		(23 "Eco2.User" user "User.Eco2")
		(25 "Edge.Cuts" user "Board Geometry/Outline")
		(27 "Margin" user)
		(31 "F.CrtYd" user "Package Geometry/Place Bound Top")
		(29 "B.CrtYd" user "Package Geometry/Place Bound Bottom")
		(35 "F.Fab" user "Ref Des/Assembly Top")
		(33 "B.Fab" user "Ref Des/Assembly Bottom")
	)
	(footprint ""
		(layer "F.Cu")
		(at 463.1944 -8.128 -90)
		(property "Reference" "R141"
			(at 0 0 270)
			(layer "F.SilkS")
			(hide yes)
			(effects
				(font
					(size 1.27 1.27)
				)
			)
		)
		(property "Value" "4K7R2F-GP"
			(at 0.064008 -3.993896 270)
			(unlocked yes)
			(layer "F.Fab")
			(hide yes)
			(effects
				(font
					(size 1.016 1.016)
					(thickness 0.1524)
				)
			)
		)
		(property "Device Type" "R402H16"
			(at 0.064008 -5.517896 270)
			(unlocked yes)
			(layer "F.Fab")
			(hide yes)
			(effects
				(font
					(size 1.016 1.016)
					(thickness 0.1524)
				)
			)
		)
		(duplicate_pad_numbers_are_jumpers no)
		(fp_line
			(start -0.508 -0.9398)
			(end -0.508 0.9398)
			(stroke
				(width 0.1524)
				(type default)
			)
			(layer "F.SilkS")
		)
		(fp_line
			(start 0.508 -0.9398)
			(end -0.508 -0.9398)
			(stroke
				(width 0.1524)
				(type default)
			)
			(layer "F.SilkS")
		)
		(fp_rect
			(start -0.508 0.9398)
			(end 0.508 -0.9398)
			(stroke
				(width 0)
				(type default)
			)
			(fill no)
			(layer "F.CrtYd")
		)
		(fp_rect
			(start -0.508 0.9398)
			(end 0.508 -0.9398)
			(stroke
				(width 0)
				(type default)
			)
			(fill no)
			(layer "F.Fab")
		)
		(pad "1" smd custom
			(at 0 -0.4445 270)
			(size 0.1397 0.1397)
			(layers "F.Cu" "F.Mask" "F.Paste")
			(net "TEMP2_A0")
			(options
				(clearance outline)
				(anchor circle)
			)
			(primitives
				(gr_poly
					(pts
						(arc
							(start -0.1778 -0.2794)
							(mid -0.249642 -0.249642)
							(end -0.2794 -0.1778)
						)
						(arc
							(start -0.2794 0.1778)
							(mid -0.249642 0.249642)
							(end -0.1778 0.2794)
						)
						(arc
							(start 0.1778 0.2794)
							(mid 0.249642 0.249642)
							(end 0.2794 0.1778)
						)
						(arc
							(start 0.2794 -0.1778)
							(mid 0.249642 -0.249642)
							(end 0.1778 -0.2794)
						)
					)
					(width 0)
					(fill yes)
				)
			)
		)
		(pad "2" smd custom
			(at 0 0.4445 270)
			(size 0.1397 0.1397)
			(layers "F.Cu" "F.Mask" "F.Paste")
			(net "GND")
			(options
				(clearance outline)
				(anchor circle)
			)
			(primitives
				(gr_poly
					(pts
						(arc
							(start -0.1778 -0.2794)
							(mid -0.249642 -0.249642)
							(end -0.2794 -0.1778)
						)
						(arc
							(start -0.2794 0.1778)
							(mid -0.249642 0.249642)
							(end -0.1778 0.2794)
						)
						(arc
							(start 0.1778 0.2794)
							(mid 0.249642 0.249642)
							(end 0.2794 0.1778)
						)
						(arc
							(start 0.2794 -0.1778)
							(mid 0.249642 -0.249642)
							(end 0.1778 -0.2794)
						)
					)
					(width 0)
					(fill yes)
				)
			)
		)
	)
	(footprint ""
		(layer "F.Cu")
		(at 41.275 -5.3594 -90)
		(property "Reference" "R129"
			(at 0 0 270)
			(layer "F.SilkS")
			(hide yes)
			(effects
				(font
					(size 1.27 1.27)
				)
			)
		)
		(property "Value" "4K7R2F-GP"
			(at 0.064008 -3.993896 270)
			(unlocked yes)
			(layer "F.Fab")
			(hide yes)
			(effects
				(font
					(size 1.016 1.016)
					(thickness 0.1524)
				)
			)
		)
		(property "Device Type" "R402H16"
			(at 0.064008 -5.517896 270)
			(unlocked yes)
			(layer "F.Fab")
			(hide yes)
			(effects
				(font
					(size 1.016 1.016)
					(thickness 0.1524)
				)
			)
		)
		(duplicate_pad_numbers_are_jumpers no)
		(fp_line
			(start -0.508 -0.9398)
			(end -0.508 0.9398)
			(stroke
				(width 0.1524)
				(type default)
			)
			(layer "F.SilkS")
		)
		(fp_line
			(start 0.508 -0.9398)
			(end -0.508 -0.9398)
			(stroke
				(width 0.1524)
				(type default)
			)
			(layer "F.SilkS")
		)
		(fp_rect
			(start -0.508 0.9398)
			(end 0.508 -0.9398)
			(stroke
				(width 0)
				(type default)
			)
			(fill no)
			(layer "F.CrtYd")
		)
		(fp_rect
			(start -0.508 0.9398)
			(end 0.508 -0.9398)
			(stroke
				(width 0)
				(type default)
			)
			(fill no)
			(layer "F.Fab")
		)
		(pad "1" smd custom
			(at 0 -0.4445 270)
			(size 0.1397 0.1397)
			(layers "F.Cu" "F.Mask" "F.Paste")
			(net "TEMP1_A2")
			(options
				(clearance outline)
				(anchor circle)
			)
			(primitives
				(gr_poly
					(pts
						(arc
							(start -0.1778 -0.2794)
							(mid -0.249642 -0.249642)
							(end -0.2794 -0.1778)
						)
						(arc
							(start -0.2794 0.1778)
							(mid -0.249642 0.249642)
							(end -0.1778 0.2794)
						)
						(arc
							(start 0.1778 0.2794)
							(mid 0.249642 0.249642)
							(end 0.2794 0.1778)
						)
						(arc
							(start 0.2794 -0.1778)
							(mid 0.249642 -0.249642)
							(end 0.1778 -0.2794)
						)
					)
					(width 0)
					(fill yes)
				)
			)
		)
		(pad "2" smd custom
			(at 0 0.4445 270)
			(size 0.1397 0.1397)
			(layers "F.Cu" "F.Mask" "F.Paste")
			(net "GND")
			(options
				(clearance outline)
				(anchor circle)
			)
			(primitives
				(gr_poly
					(pts
						(arc
							(start -0.1778 -0.2794)
							(mid -0.249642 -0.249642)
							(end -0.2794 -0.1778)
						)
						(arc
							(start -0.2794 0.1778)
							(mid -0.249642 0.249642)
							(end -0.1778 0.2794)
						)
						(arc
							(start 0.1778 0.2794)
							(mid 0.249642 0.249642)
							(end 0.2794 0.1778)
						)
						(arc
							(start 0.2794 -0.1778)
							(mid 0.249642 -0.249642)
							(end 0.1778 -0.2794)
						)
					)
					(width 0)
					(fill yes)
				)
			)
		)
	)
	(footprint ""
		(layer "F.Cu")
		(at 394.462 -10.16)
		(property "Reference" "R818"
			(at 0 0 0)
			(layer "F.SilkS")
			(hide yes)
			(effects
				(font
					(size 1.27 1.27)
				)
			)
		)
		(property "Value" "4K7R2F-GP"
			(at 0.064008 -3.993896 0)
			(unlocked yes)
			(layer "F.Fab")
			(hide yes)
			(effects
				(font
					(size 1.016 1.016)
					(thickness 0.1524)
				)
			)
		)
		(property "Device Type" "R402H16"
			(at 0.064008 -5.517896 0)
			(unlocked yes)
			(layer "F.Fab")
			(hide yes)
			(effects
				(font
					(size 1.016 1.016)
					(thickness 0.1524)
				)
			)
		)
		(duplicate_pad_numbers_are_jumpers no)
		(fp_line
			(start -0.508 -0.9398)
			(end -0.508 0.9398)
			(stroke
				(width 0.1524)
				(type default)
			)
			(layer "F.SilkS")
		)
		(fp_line
			(start 0.508 -0.9398)
			(end -0.508 -0.9398)
			(stroke
				(width 0.1524)
				(type default)
			)
			(layer "F.SilkS")
		)
		(fp_rect
			(start -0.508 0.9398)
			(end 0.508 -0.9398)
			(stroke
				(width 0)
				(type default)
			)
			(fill no)
			(layer "F.CrtYd")
		)
		(fp_rect
			(start -0.508 0.9398)
			(end 0.508 -0.9398)
			(stroke
				(width 0)
				(type default)
			)
			(fill no)
			(layer "F.Fab")
		)
		(pad "1" smd custom
			(at 0 -0.4445)
			(size 0.1397 0.1397)
			(layers "F.Cu" "F.Mask" "F.Paste")
			(net "SW_PWR_R_HDD32")
			(options
				(clearance outline)
				(anchor circle)
			)
			(primitives
				(gr_poly
					(pts
						(arc
							(start -0.1778 -0.2794)
							(mid -0.249642 -0.249642)
							(end -0.2794 -0.1778)
						)
						(arc
							(start -0.2794 0.1778)
							(mid -0.249642 0.249642)
							(end -0.1778 0.2794)
						)
						(arc
							(start 0.1778 0.2794)
							(mid 0.249642 0.249642)
							(end 0.2794 0.1778)
						)
						(arc
							(start 0.2794 -0.1778)
							(mid 0.249642 -0.249642)
							(end 0.1778 -0.2794)
						)
					)
					(width 0)
					(fill yes)
				)
			)
		)
		(pad "2" smd custom
			(at 0 0.4445)
			(size 0.1397 0.1397)
			(layers "F.Cu" "F.Mask" "F.Paste")
			(net "GND")
			(options
				(clearance outline)
				(anchor circle)
			)
			(primitives
				(gr_poly
					(pts
						(arc
							(start -0.1778 -0.2794)
							(mid -0.249642 -0.249642)
							(end -0.2794 -0.1778)
						)
						(arc
							(start -0.2794 0.1778)
							(mid -0.249642 0.249642)
							(end -0.1778 0.2794)
						)
						(arc
							(start 0.1778 0.2794)
							(mid 0.249642 0.249642)
							(end 0.2794 0.1778)
						)
						(arc
							(start 0.2794 -0.1778)
							(mid 0.249642 -0.249642)
							(end 0.1778 -0.2794)
						)
					)
					(width 0)
					(fill yes)
				)
			)
		)
	)
	(footprint ""
		(layer "F.Cu")
		(at 54.61 -248.4374 -90)
		(property "Reference" "R180"
			(at 0 0 270)
			(layer "F.SilkS")
			(hide yes)
			(effects
				(font
					(size 1.27 1.27)
				)
			)
		)
		(property "Value" "1KR2F-3-GP"
			(at 0.064008 -3.993896 270)
			(unlocked yes)
			(layer "F.Fab")
			(hide yes)
			(effects
				(font
					(size 1.016 1.016)
					(thickness 0.1524)
				)
			)
		)
		(property "Device Type" "R402H16"
			(at 0.064008 -5.517896 270)
			(unlocked yes)
			(layer "F.Fab")
			(hide yes)
			(effects
				(font
					(size 1.016 1.016)
					(thickness 0.1524)
				)
			)
		)
		(duplicate_pad_numbers_are_jumpers no)
		(fp_line
			(start -0.508 -0.9398)
			(end -0.508 0.9398)
			(stroke
				(width 0.1524)
				(type default)
			)
			(layer "F.SilkS")
		)
		(fp_line
			(start 0.508 -0.9398)
			(end -0.508 -0.9398)
			(stroke
				(width 0.1524)
				(type default)
			)
			(layer "F.SilkS")
		)
		(fp_rect
			(start -0.508 0.9398)
			(end 0.508 -0.9398)
			(stroke
				(width 0)
				(type default)
			)
			(fill no)
			(layer "F.CrtYd")
		)
		(fp_rect
			(start -0.508 0.9398)
			(end 0.508 -0.9398)
			(stroke
				(width 0)
				(type default)
			)
			(fill no)
			(layer "F.Fab")
		)
		(pad "1" smd custom
			(at 0 -0.4445 270)
			(size 0.1397 0.1397)
			(layers "F.Cu" "F.Mask" "F.Paste")
			(net "P3V3_STBY_B")
			(options
				(clearance outline)
				(anchor circle)
			)
			(primitives
				(gr_poly
					(pts
						(arc
							(start -0.1778 -0.2794)
							(mid -0.249642 -0.249642)
							(end -0.2794 -0.1778)
						)
						(arc
							(start -0.2794 0.1778)
							(mid -0.249642 0.249642)
							(end -0.1778 0.2794)
						)
						(arc
							(start 0.1778 0.2794)
							(mid 0.249642 0.249642)
							(end 0.2794 0.1778)
						)
						(arc
							(start 0.2794 -0.1778)
							(mid 0.249642 -0.249642)
							(end 0.1778 -0.2794)
						)
					)
					(width 0)
					(fill yes)
				)
			)
		)
		(pad "2" smd custom
			(at 0 0.4445 270)
			(size 0.1397 0.1397)
			(layers "F.Cu" "F.Mask" "F.Paste")
			(net "SW_PWR_R_HDD1")
			(options
				(clearance outline)
				(anchor circle)
			)
			(primitives
				(gr_poly
					(pts
						(arc
							(start -0.1778 -0.2794)
							(mid -0.249642 -0.249642)
							(end -0.2794 -0.1778)
						)
						(arc
							(start -0.2794 0.1778)
							(mid -0.249642 0.249642)
							(end -0.1778 0.2794)
						)
						(arc
							(start 0.1778 0.2794)
							(mid 0.249642 0.249642)
							(end 0.2794 0.1778)
						)
						(arc
							(start 0.2794 -0.1778)
							(mid 0.249642 -0.249642)
							(end 0.1778 -0.2794)
						)
					)
					(width 0)
					(fill yes)
				)
			)
		)
	)
	(footprint ""
		(layer "F.Cu")
		(at 302.393096 -327.858882)
		(property "Reference" "R96"
			(at 0 0 0)
			(layer "F.SilkS")
			(hide yes)
			(effects
				(font
					(size 1.27 1.27)
				)
			)
		)
		(property "Value" "100KR2F-L1-GP"
			(at 0.064008 -3.993896 0)
			(unlocked yes)
			(layer "F.Fab")
			(hide yes)
			(effects
				(font
					(size 1.016 1.016)
					(thickness 0.1524)
				)
			)
		)
		(property "Device Type" "R402H16"
			(at 0.064008 -5.517896 0)
			(unlocked yes)
			(layer "F.Fab")
			(hide yes)
			(effects
				(font
					(size 1.016 1.016)
					(thickness 0.1524)
				)
			)
		)
		(duplicate_pad_numbers_are_jumpers no)
		(fp_line
			(start -0.508 -0.9398)
			(end -0.508 0.9398)
			(stroke
				(width 0.1524)
				(type default)
			)
			(layer "F.SilkS")
		)
		(fp_line
			(start 0.508 -0.9398)
			(end -0.508 -0.9398)
			(stroke
				(width 0.1524)
				(type default)
			)
			(layer "F.SilkS")
		)
		(fp_rect
			(start -0.508 0.9398)
			(end 0.508 -0.9398)
			(stroke
				(width 0)
				(type default)
			)
			(fill no)
			(layer "F.CrtYd")
		)
		(fp_rect
			(start -0.508 0.9398)
			(end 0.508 -0.9398)
			(stroke
				(width 0)
				(type default)
			)
			(fill no)
			(layer "F.Fab")
		)
		(pad "1" smd custom
			(at 0 -0.4445)
			(size 0.1397 0.1397)
			(layers "F.Cu" "F.Mask" "F.Paste")
			(net "PWM_SCC_A_ZONE_C")
			(options
				(clearance outline)
				(anchor circle)
			)
			(primitives
				(gr_poly
					(pts
						(arc
							(start -0.1778 -0.2794)
							(mid -0.249642 -0.249642)
							(end -0.2794 -0.1778)
						)
						(arc
							(start -0.2794 0.1778)
							(mid -0.249642 0.249642)
							(end -0.1778 0.2794)
						)
						(arc
							(start 0.1778 0.2794)
							(mid 0.249642 0.249642)
							(end 0.2794 0.1778)
						)
						(arc
							(start 0.2794 -0.1778)
							(mid 0.249642 -0.249642)
							(end 0.1778 -0.2794)
						)
					)
					(width 0)
					(fill yes)
				)
			)
		)
		(pad "2" smd custom
			(at 0 0.4445)
			(size 0.1397 0.1397)
			(layers "F.Cu" "F.Mask" "F.Paste")
			(net "GND")
			(options
				(clearance outline)
				(anchor circle)
			)
			(primitives
				(gr_poly
					(pts
						(arc
							(start -0.1778 -0.2794)
							(mid -0.249642 -0.249642)
							(end -0.2794 -0.1778)
						)
						(arc
							(start -0.2794 0.1778)
							(mid -0.249642 0.249642)
							(end -0.1778 0.2794)
						)
						(arc
							(start 0.1778 0.2794)
							(mid 0.249642 0.249642)
							(end 0.2794 0.1778)
						)
						(arc
							(start 0.2794 -0.1778)
							(mid 0.249642 -0.249642)
							(end 0.1778 -0.2794)
						)
					)
					(width 0)
					(fill yes)
				)
			)
		)
	)
	(footprint ""
		(layer "F.Cu")
		(at 423.958004 -365.379 -90)
		(property "Reference" "R960"
			(at 0 0 270)
			(layer "F.SilkS")
			(hide yes)
			(effects
				(font
					(size 1.27 1.27)
				)
			)
		)
		(property "Value" "27KR3F-GP"
			(at -0.0254 -2.5146 270)
			(unlocked yes)
			(layer "F.Fab")
			(hide yes)
			(effects
				(font
					(size 1.016 1.016)
					(thickness 0.1524)
				)
			)
		)
		(property "Device Type" "R603H22"
			(at -0.0254 -4.0386 270)
			(unlocked yes)
			(layer "F.Fab")
			(hide yes)
			(effects
				(font
					(size 1.016 1.016)
					(thickness 0.1524)
				)
			)
		)
		(duplicate_pad_numbers_are_jumpers no)
		(fp_line
			(start -0.4826 0)
			(end -0.2032 0)
			(stroke
				(width 0.2032)
				(type default)
			)
			(layer "F.SilkS")
		)
		(fp_line
			(start 0.2032 0)
			(end 0.4826 0)
			(stroke
				(width 0.2032)
				(type default)
			)
			(layer "F.SilkS")
		)
		(fp_rect
			(start -0.5842 1.3335)
			(end 0.5842 -1.3335)
			(stroke
				(width 0)
				(type default)
			)
			(fill no)
			(layer "F.CrtYd")
		)
		(fp_rect
			(start -0.5842 1.3335)
			(end 0.5842 -1.3335)
			(stroke
				(width 0)
				(type default)
			)
			(fill no)
			(layer "F.Fab")
		)
		(pad "1" smd custom
			(at 0 -0.762 270)
			(size 0.2159 0.2159)
			(layers "F.Cu" "F.Mask" "F.Paste")
			(net "FAN_3_TACH1")
			(options
				(clearance outline)
				(anchor circle)
			)
			(primitives
				(gr_poly
					(pts
						(arc
							(start -0.3302 -0.4318)
							(mid -0.402042 -0.402042)
							(end -0.4318 -0.3302)
						)
						(arc
							(start -0.4318 0.3302)
							(mid -0.402042 0.402042)
							(end -0.3302 0.4318)
						)
						(arc
							(start 0.3302 0.4318)
							(mid 0.402042 0.402042)
							(end 0.4318 0.3302)
						)
						(arc
							(start 0.4318 -0.3302)
							(mid 0.402042 -0.402042)
							(end 0.3302 -0.4318)
						)
					)
					(width 0)
					(fill yes)
				)
			)
		)
		(pad "2" smd custom
			(at 0 0.762 270)
			(size 0.2159 0.2159)
			(layers "F.Cu" "F.Mask" "F.Paste")
			(net "FANTACH_F3")
			(options
				(clearance outline)
				(anchor circle)
			)
			(primitives
				(gr_poly
					(pts
						(arc
							(start -0.3302 -0.4318)
							(mid -0.402042 -0.402042)
							(end -0.4318 -0.3302)
						)
						(arc
							(start -0.4318 0.3302)
							(mid -0.402042 0.402042)
							(end -0.3302 0.4318)
						)
						(arc
							(start 0.3302 0.4318)
							(mid 0.402042 0.402042)
							(end 0.4318 0.3302)
						)
						(arc
							(start 0.4318 -0.3302)
							(mid 0.402042 -0.402042)
							(end 0.3302 -0.4318)
						)
					)
					(width 0)
					(fill yes)
				)
			)
		)
	)
	(footprint ""
		(layer "F.Cu")
		(at 182.372 -370.459 90)
		(property "Reference" "R988"
			(at 0 0 90)
			(layer "F.SilkS")
			(hide yes)
			(effects
				(font
					(size 1.27 1.27)
				)
			)
		)
		(property "Value" "0R2J-2-GP"
			(at 0.064008 -3.993896 90)
			(unlocked yes)
			(layer "F.Fab")
			(hide yes)
			(effects
				(font
					(size 1.016 1.016)
					(thickness 0.1524)
				)
			)
		)
		(property "Device Type" "R402H16"
			(at 0.064008 -5.517896 90)
			(unlocked yes)
			(layer "F.Fab")
			(hide yes)
			(effects
				(font
					(size 1.016 1.016)
					(thickness 0.1524)
				)
			)
		)
		(duplicate_pad_numbers_are_jumpers no)
		(fp_line
			(start 0.508 -0.9398)
			(end -0.508 -0.9398)
			(stroke
				(width 0.1524)
				(type default)
			)
			(layer "F.SilkS")
		)
		(fp_line
			(start -0.508 -0.9398)
			(end -0.508 0.9398)
			(stroke
				(width 0.1524)
				(type default)
			)
			(layer "F.SilkS")
		)
		(fp_rect
			(start -0.508 0.9398)
			(end 0.508 -0.9398)
			(stroke
				(width 0)
				(type default)
			)
			(fill no)
			(layer "F.CrtYd")
		)
		(fp_rect
			(start -0.508 0.9398)
			(end 0.508 -0.9398)
			(stroke
				(width 0)
				(type default)
			)
			(fill no)
			(layer "F.Fab")
		)
		(pad "1" smd custom
			(at 0 -0.4445 90)
			(size 0.1397 0.1397)
			(layers "F.Cu" "F.Mask" "F.Paste")
			(net "MB0_SDA_R")
			(options
				(clearance outline)
				(anchor circle)
			)
			(primitives
				(gr_poly
					(pts
						(arc
							(start -0.1778 -0.2794)
							(mid -0.249642 -0.249642)
							(end -0.2794 -0.1778)
						)
						(arc
							(start -0.2794 0.1778)
							(mid -0.249642 0.249642)
							(end -0.1778 0.2794)
						)
						(arc
							(start 0.1778 0.2794)
							(mid 0.249642 0.249642)
							(end 0.2794 0.1778)
						)
						(arc
							(start 0.2794 -0.1778)
							(mid 0.249642 -0.249642)
							(end 0.1778 -0.2794)
						)
					)
					(width 0)
					(fill yes)
				)
			)
		)
		(pad "2" smd custom
			(at 0 0.4445 90)
			(size 0.1397 0.1397)
			(layers "F.Cu" "F.Mask" "F.Paste")
			(net "I2C_CLIP_B_SDA")
			(options
				(clearance outline)
				(anchor circle)
			)
			(primitives
				(gr_poly
					(pts
						(arc
							(start -0.1778 -0.2794)
							(mid -0.249642 -0.249642)
							(end -0.2794 -0.1778)
						)
						(arc
							(start -0.2794 0.1778)
							(mid -0.249642 0.249642)
							(end -0.1778 0.2794)
						)
						(arc
							(start 0.1778 0.2794)
							(mid 0.249642 0.249642)
							(end 0.2794 0.1778)
						)
						(arc
							(start 0.2794 -0.1778)
							(mid 0.249642 -0.249642)
							(end 0.1778 -0.2794)
						)
					)
					(width 0)
					(fill yes)
				)
			)
		)
	)
)
